# S9S_MB_2U (Grand Teton) — schematic netlist excerpt (pin names and nets, part order shuffled) for the footprints in the layout excerpt that follows; sources: Cadence DE-HDL packaged netlist, KiCad conversion of 03242023_DA0F0TMBIJ0_F0T_Motherboard_J_brd_V01_OCP.brd

PC1656  Q_CAP  100NF 50V 10% X7R  pkg C0402  page 285 : A = P12V_AUX ; B = GND
R3230  Q_RES  33.2 1% CHIP  pkg 0402LF  page 213 : A = FM_OCP_V3_2_PWR_GOOD ; B = FM_OCP_V3_2_PWR_GOOD_R

(kicad_pcb
	(version 20260206)
	(generator "pcbnew")
	(generator_version "10.0")
	(general
		(thickness 1.6)
		(legacy_teardrops no)
	)
	(paper "A4")
	(title_block
		(title "03242023_DA0F0TMBIJ0_F0T_Motherboard_J_brd_V01_OCP.brd")
		(comment 1 "Grand Teton / footprints 2712-2713 of 6105")
	)
	(layers
		(0 "F.Cu" signal "TOP")
		(4 "In1.Cu" signal "GND")
		(6 "In2.Cu" signal "IN1")
		(8 "In3.Cu" signal "GND1")
		(10 "In4.Cu" signal "IN2")
		(12 "In5.Cu" signal "GND2")
		(14 "In6.Cu" signal "IN3")
		(16 "In7.Cu" signal "GND3")
		(18 "In8.Cu" signal "VCC")
		(20 "In9.Cu" signal "VCC1")
		(22 "In10.Cu" signal "GND4")
		(24 "In11.Cu" signal "IN4")
		(26 "In12.Cu" signal "GND5")
		(28 "In13.Cu" signal "IN5")
		(30 "In14.Cu" signal "GND6")
		(32 "In15.Cu" signal "IN6")
		(34 "In16.Cu" signal "GND7")
		(2 "B.Cu" signal "BOTTOM")
		(9 "F.Adhes" user "F.Adhesive")
		(11 "B.Adhes" user "B.Adhesive")
		(13 "F.Paste" user "Package Geometry/Pastemask Top")
		(15 "B.Paste" user "Package Geometry/Pastemask Bottom")
		(5 "F.SilkS" user "Ref Des/Silkscreen Top")
		(7 "B.SilkS" user "Ref Des/Silkscreen Bottom")
		(1 "F.Mask" user "Board Geometry/Soldermask Top")
		(3 "B.Mask" user "Board Geometry/Soldermask Bottom")
		(17 "Dwgs.User" user "User.Drawings")
		(19 "Cmts.User" user "User.Comments")
		(21 "Eco1.User" user "User.Eco1")
		(23 "Eco2.User" user "User.Eco2")
		(25 "Edge.Cuts" user "Board Geometry/Outline")
		(27 "Margin" user)
		(31 "F.CrtYd" user "Package Geometry/Place Bound Top")
		(29 "B.CrtYd" user "Package Geometry/Place Bound Bottom")
		(35 "F.Fab" user "Ref Des/Assembly Top")
		(33 "B.Fab" user "Ref Des/Assembly Bottom")
	)
	(footprint ""
		(layer "F.Cu")
		(at 160.83788 -108.295948)
		(property "Reference" "R3230"
			(at 0 0 0)
			(layer "F.SilkS")
			(hide yes)
			(effects
				(font
					(size 1.27 1.27)
				)
			)
		)
		(property "Value" ""
			(at 0 0 0)
			(layer "F.Fab")
			(effects
				(font
					(size 1.27 1.27)
				)
			)
		)
		(duplicate_pad_numbers_are_jumpers no)
		(fp_line
			(start -0.7874 -0.4064)
			(end 0.7874 -0.4064)
			(stroke
				(width 0.1524)
				(type default)
			)
			(layer "F.SilkS")
		)
		(fp_line
			(start -0.7874 0.4064)
			(end -0.7874 -0.4064)
			(stroke
				(width 0.1524)
				(type default)
			)
			(layer "F.SilkS")
		)
		(fp_line
			(start 0.7874 -0.4064)
			(end 0.7874 0.4064)
			(stroke
				(width 0.1524)
				(type default)
			)
			(layer "F.SilkS")
		)
		(fp_line
			(start 0.7874 0.4064)
			(end -0.7874 0.4064)
			(stroke
				(width 0.1524)
				(type default)
			)
			(layer "F.SilkS")
		)
		(fp_line
			(start -0.67945 -0.305054)
			(end -0.12065 -0.305054)
			(stroke
				(width 0.1)
				(type default)
			)
			(layer "F.Fab")
		)
		(fp_line
			(start -0.67945 0.3048)
			(end -0.67945 -0.305054)
			(stroke
				(width 0.1)
				(type default)
			)
			(layer "F.Fab")
		)
		(fp_line
			(start -0.12065 -0.305054)
			(end -0.12065 -0.2794)
			(stroke
				(width 0.1)
				(type default)
			)
			(layer "F.Fab")
		)
		(fp_line
			(start -0.12065 -0.2794)
			(end 0.12065 -0.2794)
			(stroke
				(width 0.1)
				(type default)
			)
			(layer "F.Fab")
		)
		(fp_line
			(start -0.12065 0.2794)
			(end -0.12065 0.3048)
			(stroke
				(width 0.1)
				(type default)
			)
			(layer "F.Fab")
		)
		(fp_line
			(start -0.12065 0.3048)
			(end -0.67945 0.3048)
			(stroke
				(width 0.1)
				(type default)
			)
			(layer "F.Fab")
		)
		(fp_line
			(start 0.120396 0.2794)
			(end -0.12065 0.2794)
			(stroke
				(width 0.1)
				(type default)
			)
			(layer "F.Fab")
		)
		(fp_line
			(start 0.120396 0.3048)
			(end 0.120396 0.2794)
			(stroke
				(width 0.1)
				(type default)
			)
			(layer "F.Fab")
		)
		(fp_line
			(start 0.12065 -0.3048)
			(end 0.67945 -0.3048)
			(stroke
				(width 0.1)
				(type default)
			)
			(layer "F.Fab")
		)
		(fp_line
			(start 0.12065 -0.2794)
			(end 0.12065 -0.3048)
			(stroke
				(width 0.1)
				(type default)
			)
			(layer "F.Fab")
		)
		(fp_line
			(start 0.67945 -0.3048)
			(end 0.67945 0.3048)
			(stroke
				(width 0.1)
				(type default)
			)
			(layer "F.Fab")
		)
		(fp_line
			(start 0.67945 0.3048)
			(end 0.120396 0.3048)
			(stroke
				(width 0.1)
				(type default)
			)
			(layer "F.Fab")
		)
		(pad "1" smd circle
			(at -0.40005 0)
			(size 0 0)
			(layers "F.Cu" "F.Mask" "F.Paste")
			(net "FM_OCP_V3_2_PWR_GOOD")
		)
		(pad "2" smd circle
			(at 0.40005 0)
			(size 0 0)
			(layers "F.Cu" "F.Mask" "F.Paste")
			(net "FM_OCP_V3_2_PWR_GOOD_R")
		)
	)
	(footprint ""
		(layer "F.Cu")
		(at 97.992438 -354.88499 -90)
		(property "Reference" "PC1656"
			(at 0 0 270)
			(layer "F.SilkS")
			(hide yes)
			(effects
				(font
					(size 1.27 1.27)
				)
			)
		)
		(property "Value" ""
			(at 0 0 270)
			(layer "F.Fab")
			(effects
				(font
					(size 1.27 1.27)
				)
			)
		)
		(duplicate_pad_numbers_are_jumpers no)
		(fp_line
			(start -0.7874 0.4064)
			(end -0.7874 -0.4064)
			(stroke
				(width 0.1524)
				(type default)
			)
			(layer "F.SilkS")
		)
		(fp_line
			(start 0.7874 0.4064)
			(end -0.7874 0.4064)
			(stroke
				(width 0.1524)
				(type default)
			)
			(layer "F.SilkS")
		)
		(fp_line
			(start -0.7874 -0.4064)
			(end 0.7874 -0.4064)
			(stroke
				(width 0.1524)
				(type default)
			)
			(layer "F.SilkS")
		)
		(fp_line
			(start 0.7874 -0.4064)
			(end 0.7874 0.4064)
			(stroke
				(width 0.1524)
				(type default)
			)
			(layer "F.SilkS")
		)
		(fp_line
			(start -0.67945 0.3048)
			(end -0.67945 -0.305054)
			(stroke
				(width 0.1)
				(type default)
			)
			(layer "F.Fab")
		)
		(fp_line
			(start -0.12065 0.3048)
			(end -0.67945 0.3048)
			(stroke
				(width 0.1)
				(type default)
			)
			(layer "F.Fab")
		)
		(fp_line
			(start 0.120396 0.3048)
			(end 0.120396 0.2794)
			(stroke
				(width 0.1)
				(type default)
			)
			(layer "F.Fab")
		)
		(fp_line
			(start 0.67945 0.3048)
			(end 0.120396 0.3048)
			(stroke
				(width 0.1)
				(type default)
			)
			(layer "F.Fab")
		)
		(fp_line
			(start -0.12065 0.2794)
			(end -0.12065 0.3048)
			(stroke
				(width 0.1)
				(type default)
			)
			(layer "F.Fab")
		)
		(fp_line
			(start 0.120396 0.2794)
			(end -0.12065 0.2794)
			(stroke
				(width 0.1)
				(type default)
			)
			(layer "F.Fab")
		)
		(fp_line
			(start -0.12065 -0.2794)
			(end 0.12065 -0.2794)
			(stroke
				(width 0.1)
				(type default)
			)
			(layer "F.Fab")
		)
		(fp_line
			(start 0.12065 -0.2794)
			(end 0.12065 -0.3048)
			(stroke
				(width 0.1)
				(type default)
			)
			(layer "F.Fab")
		)
		(fp_line
			(start 0.12065 -0.3048)
			(end 0.67945 -0.3048)
			(stroke
				(width 0.1)
				(type default)
			)
			(layer "F.Fab")
		)
		(fp_line
			(start 0.67945 -0.3048)
			(end 0.67945 0.3048)
			(stroke
				(width 0.1)
				(type default)
			)
			(layer "F.Fab")
		)
		(fp_line
			(start -0.67945 -0.305054)
			(end -0.12065 -0.305054)
			(stroke
				(width 0.1)
				(type default)
			)
			(layer "F.Fab")
		)
		(fp_line
			(start -0.12065 -0.305054)
			(end -0.12065 -0.2794)
			(stroke
				(width 0.1)
				(type default)
			)
			(layer "F.Fab")
		)
		(pad "1" smd circle
			(at -0.40005 0 270)
			(size 0 0)
			(layers "F.Cu" "F.Mask" "F.Paste")
			(net "P12V_AUX")
		)
		(pad "2" smd circle
			(at 0.40005 0 270)
			(size 0 0)
			(layers "F.Cu" "F.Mask" "F.Paste")
			(net "GND")
		)
	)
)
